# T6G (Grand Teton) — schematic netlist excerpt (pin names and nets, part order shuffled) for the footprints in the layout excerpt that follows; sources: Cadence DE-HDL packaged netlist, KiCad conversion of 04192023_DAF0TMB3IC0_F0TG_MB_C_brd_V02_OCP.brd

C69  Q_CAP  0.1UF 25V 10% X7R  pkg 0402  page 241 : A = P3V3_AUX ; B = GND
C1559  Q_CAP_DIFFBUS  DIFF BUS_0.22UF 6.3V 20% X6S  pkg C0201  page 65 : \1\ = P5E_CPU0_G3_TX_C_DP<10> ; \2\ = P5E_CPU0_G3_TX_DP<10>
PC270  Q_CAP  0.22UF 16V 10% X7R  pkg 0402  page 211 : A = SW_PVDDCR_CPU0_P1_BOOT1_RC ; B = SW_PVDDCR_CPU0_P1_PH1

(kicad_pcb
	(version 20260206)
	(generator "pcbnew")
	(generator_version "10.0")
	(general
		(thickness 1.6)
		(legacy_teardrops no)
	)
	(paper "A4")
	(title_block
		(title "04192023_DAF0TMB3IC0_F0TG_MB_C_brd_V02_OCP.brd")
		(comment 1 "Grand Teton / footprints 1103-1105 of 8354")
	)
	(layers
		(0 "F.Cu" signal "TOP")
		(4 "In1.Cu" signal "GND")
		(6 "In2.Cu" signal "IN1")
		(8 "In3.Cu" signal "GND1")
		(10 "In4.Cu" signal "IN2")
		(12 "In5.Cu" signal "GND2")
		(14 "In6.Cu" signal "IN3")
		(16 "In7.Cu" signal "GND3")
		(18 "In8.Cu" signal "VCC")
		(20 "In9.Cu" signal "VCC1")
		(22 "In10.Cu" signal "GND4")
		(24 "In11.Cu" signal "IN4")
		(26 "In12.Cu" signal "GND5")
		(28 "In13.Cu" signal "IN5")
		(30 "In14.Cu" signal "GND6")
		(32 "In15.Cu" signal "IN6")
		(34 "In16.Cu" signal "GND7")
		(2 "B.Cu" signal "BOTTOM")
		(9 "F.Adhes" user "F.Adhesive")
		(11 "B.Adhes" user "B.Adhesive")
		(13 "F.Paste" user "Package Geometry/Pastemask Top")
		(15 "B.Paste" user "Package Geometry/Pastemask Bottom")
		(5 "F.SilkS" user "Ref Des/Silkscreen Top")
		(7 "B.SilkS" user "Ref Des/Silkscreen Bottom")
		(1 "F.Mask" user "Board Geometry/Soldermask Top")
		(3 "B.Mask" user "Board Geometry/Soldermask Bottom")
		(17 "Dwgs.User" user "User.Drawings")
		(19 "Cmts.User" user "User.Comments")
		(21 "Eco1.User" user "User.Eco1")
		(23 "Eco2.User" user "User.Eco2")
		(25 "Edge.Cuts" user "Board Geometry/Outline")
		(27 "Margin" user)
		(31 "F.CrtYd" user "Package Geometry/Place Bound Top")
		(29 "B.CrtYd" user "Package Geometry/Place Bound Bottom")
		(35 "F.Fab" user "Ref Des/Assembly Top")
		(33 "B.Fab" user "Ref Des/Assembly Bottom")
	)
	(footprint ""
		(layer "F.Cu")
		(at 278.254206 -431.191416 -90)
		(property "Reference" "C69"
			(at 0 0 270)
			(layer "F.SilkS")
			(hide yes)
			(effects
				(font
					(size 1.27 1.27)
				)
			)
		)
		(property "Value" ""
			(at 0 0 270)
			(layer "F.Fab")
			(effects
				(font
					(size 1.27 1.27)
				)
			)
		)
		(duplicate_pad_numbers_are_jumpers no)
		(fp_line
			(start -0.7874 0.4064)
			(end -0.7874 -0.4064)
			(stroke
				(width 0.1524)
				(type default)
			)
			(layer "F.SilkS")
		)
		(fp_line
			(start 0.7874 0.4064)
			(end -0.7874 0.4064)
			(stroke
				(width 0.1524)
				(type default)
			)
			(layer "F.SilkS")
		)
		(fp_line
			(start -0.7874 -0.4064)
			(end 0.7874 -0.4064)
			(stroke
				(width 0.1524)
				(type default)
			)
			(layer "F.SilkS")
		)
		(fp_line
			(start 0.7874 -0.4064)
			(end 0.7874 0.4064)
			(stroke
				(width 0.1524)
				(type default)
			)
			(layer "F.SilkS")
		)
		(fp_line
			(start -0.67945 0.3048)
			(end -0.67945 -0.305054)
			(stroke
				(width 0.1)
				(type default)
			)
			(layer "F.Fab")
		)
		(fp_line
			(start -0.12065 0.3048)
			(end -0.67945 0.3048)
			(stroke
				(width 0.1)
				(type default)
			)
			(layer "F.Fab")
		)
		(fp_line
			(start 0.120396 0.3048)
			(end 0.120396 0.2794)
			(stroke
				(width 0.1)
				(type default)
			)
			(layer "F.Fab")
		)
		(fp_line
			(start 0.67945 0.3048)
			(end 0.120396 0.3048)
			(stroke
				(width 0.1)
				(type default)
			)
			(layer "F.Fab")
		)
		(fp_line
			(start -0.12065 0.2794)
			(end -0.12065 0.3048)
			(stroke
				(width 0.1)
				(type default)
			)
			(layer "F.Fab")
		)
		(fp_line
			(start 0.120396 0.2794)
			(end -0.12065 0.2794)
			(stroke
				(width 0.1)
				(type default)
			)
			(layer "F.Fab")
		)
		(fp_line
			(start -0.12065 -0.2794)
			(end 0.12065 -0.2794)
			(stroke
				(width 0.1)
				(type default)
			)
			(layer "F.Fab")
		)
		(fp_line
			(start 0.12065 -0.2794)
			(end 0.12065 -0.3048)
			(stroke
				(width 0.1)
				(type default)
			)
			(layer "F.Fab")
		)
		(fp_line
			(start 0.12065 -0.3048)
			(end 0.67945 -0.3048)
			(stroke
				(width 0.1)
				(type default)
			)
			(layer "F.Fab")
		)
		(fp_line
			(start 0.67945 -0.3048)
			(end 0.67945 0.3048)
			(stroke
				(width 0.1)
				(type default)
			)
			(layer "F.Fab")
		)
		(fp_line
			(start -0.67945 -0.305054)
			(end -0.12065 -0.305054)
			(stroke
				(width 0.1)
				(type default)
			)
			(layer "F.Fab")
		)
		(fp_line
			(start -0.12065 -0.305054)
			(end -0.12065 -0.2794)
			(stroke
				(width 0.1)
				(type default)
			)
			(layer "F.Fab")
		)
		(pad "1" smd circle
			(at -0.40005 0 270)
			(size 0 0)
			(layers "F.Cu" "F.Mask" "F.Paste")
			(net "P3V3_AUX")
		)
		(pad "2" smd circle
			(at 0.40005 0 270)
			(size 0 0)
			(layers "F.Cu" "F.Mask" "F.Paste")
			(net "GND")
		)
	)
	(footprint ""
		(layer "F.Cu")
		(at 404.891748 -17.624298 90)
		(property "Reference" "C1559"
			(at 0 0 90)
			(layer "F.SilkS")
			(hide yes)
			(effects
				(font
					(size 1.27 1.27)
				)
			)
		)
		(property "Value" ""
			(at 0 0 90)
			(layer "F.Fab")
			(effects
				(font
					(size 1.27 1.27)
				)
			)
		)
		(duplicate_pad_numbers_are_jumpers no)
		(fp_line
			(start 0.299974 -0.150114)
			(end 0.299974 0.150114)
			(stroke
				(width 0.1)
				(type default)
			)
			(layer "F.Fab")
		)
		(fp_line
			(start -0.299974 -0.150114)
			(end 0.299974 -0.150114)
			(stroke
				(width 0.1)
				(type default)
			)
			(layer "F.Fab")
		)
		(fp_line
			(start 0.299974 0.150114)
			(end -0.299974 0.150114)
			(stroke
				(width 0.1)
				(type default)
			)
			(layer "F.Fab")
		)
		(fp_line
			(start -0.299974 0.150114)
			(end -0.299974 -0.150114)
			(stroke
				(width 0.1)
				(type default)
			)
			(layer "F.Fab")
		)
		(pad "1" smd rect
			(at -0.2667 0 90)
			(size 0.3048 0.381)
			(layers "F.Cu" "F.Mask" "F.Paste")
			(net "P5E_CPU0_G3_TX_C_DP<10>")
		)
		(pad "2" smd rect
			(at 0.2667 0 90)
			(size 0.3048 0.381)
			(layers "F.Cu" "F.Mask" "F.Paste")
			(net "P5E_CPU0_G3_TX_DP<10>")
		)
	)
	(footprint ""
		(layer "F.Cu")
		(at 80.498696 -178.0921 90)
		(property "Reference" "PC270"
			(at 0 0 90)
			(layer "F.SilkS")
			(hide yes)
			(effects
				(font
					(size 1.27 1.27)
				)
			)
		)
		(property "Value" ""
			(at 0 0 90)
			(layer "F.Fab")
			(effects
				(font
					(size 1.27 1.27)
				)
			)
		)
		(duplicate_pad_numbers_are_jumpers no)
		(fp_line
			(start 0.7874 -0.4064)
			(end 0.7874 0.4064)
			(stroke
				(width 0.1524)
				(type default)
			)
			(layer "F.SilkS")
		)
		(fp_line
			(start -0.7874 -0.4064)
			(end 0.7874 -0.4064)
			(stroke
				(width 0.1524)
				(type default)
			)
			(layer "F.SilkS")
		)
		(fp_line
			(start 0.7874 0.4064)
			(end -0.7874 0.4064)
			(stroke
				(width 0.1524)
				(type default)
			)
			(layer "F.SilkS")
		)
		(fp_line
			(start -0.7874 0.4064)
			(end -0.7874 -0.4064)
			(stroke
				(width 0.1524)
				(type default)
			)
			(layer "F.SilkS")
		)
		(fp_line
			(start -0.12065 -0.305054)
			(end -0.12065 -0.2794)
			(stroke
				(width 0.1)
				(type default)
			)
			(layer "F.Fab")
		)
		(fp_line
			(start -0.67945 -0.305054)
			(end -0.12065 -0.305054)
			(stroke
				(width 0.1)
				(type default)
			)
			(layer "F.Fab")
		)
		(fp_line
			(start 0.67945 -0.3048)
			(end 0.67945 0.3048)
			(stroke
				(width 0.1)
				(type default)
			)
			(layer "F.Fab")
		)
		(fp_line
			(start 0.12065 -0.3048)
			(end 0.67945 -0.3048)
			(stroke
				(width 0.1)
				(type default)
			)
			(layer "F.Fab")
		)
		(fp_line
			(start 0.12065 -0.2794)
			(end 0.12065 -0.3048)
			(stroke
				(width 0.1)
				(type default)
			)
			(layer "F.Fab")
		)
		(fp_line
			(start -0.12065 -0.2794)
			(end 0.12065 -0.2794)
			(stroke
				(width 0.1)
				(type default)
			)
			(layer "F.Fab")
		)
		(fp_line
			(start 0.120396 0.2794)
			(end -0.12065 0.2794)
			(stroke
				(width 0.1)
				(type default)
			)
			(layer "F.Fab")
		)
		(fp_line
			(start -0.12065 0.2794)
			(end -0.12065 0.3048)
			(stroke
				(width 0.1)
				(type default)
			)
			(layer "F.Fab")
		)
		(fp_line
			(start 0.67945 0.3048)
			(end 0.120396 0.3048)
			(stroke
				(width 0.1)
				(type default)
			)
			(layer "F.Fab")
		)
		(fp_line
			(start 0.120396 0.3048)
			(end 0.120396 0.2794)
			(stroke
				(width 0.1)
				(type default)
			)
			(layer "F.Fab")
		)
		(fp_line
			(start -0.12065 0.3048)
			(end -0.67945 0.3048)
			(stroke
				(width 0.1)
				(type default)
			)
			(layer "F.Fab")
		)
		(fp_line
			(start -0.67945 0.3048)
			(end -0.67945 -0.305054)
			(stroke
				(width 0.1)
				(type default)
			)
			(layer "F.Fab")
		)
		(pad "1" smd circle
			(at -0.40005 0 90)
			(size 0 0)
			(layers "F.Cu" "F.Mask" "F.Paste")
			(net "SW_PVDDCR_CPU0_P1_BOOT1_RC")
		)
		(pad "2" smd circle
			(at 0.40005 0 90)
			(size 0 0)
			(layers "F.Cu" "F.Mask" "F.Paste")
			(net "SW_PVDDCR_CPU0_P1_PH1")
		)
	)
)
